(kicad_pcb
	(version 20260206)
	(generator "pcbnew")
	(generator_version "10.0")
	(general
		(thickness 1.6)
		(legacy_teardrops no)
	)
	(paper "A4")
	(title_block
		(title "01162023_DA0F0TEBIF0_F0T_Expander_BD_F_brd_V02_OCP.brd")
		(comment 1 "Grand Teton / footprints 1671-1677 of 9728")
	)
	(layers
		(0 "F.Cu" signal "TOP")
		(4 "In1.Cu" signal "GND")
		(6 "In2.Cu" signal "VCC")
		(8 "In3.Cu" signal "VCC1")
		(10 "In4.Cu" signal "GND1")
		(12 "In5.Cu" signal "IN1")
		(14 "In6.Cu" signal "GND2")
		(16 "In7.Cu" signal "IN2")
		(18 "In8.Cu" signal "GND3")
		(20 "In9.Cu" signal "IN3")
		(22 "In10.Cu" signal "GND4")
		(24 "In11.Cu" signal "IN4")
		(26 "In12.Cu" signal "GND5")
		(28 "In13.Cu" signal "IN5")
		(30 "In14.Cu" signal "GND6")
		(32 "In15.Cu" signal "IN6")
		(34 "In16.Cu" signal "GND7")
		(2 "B.Cu" signal "BOTTOM")
		(9 "F.Adhes" user "F.Adhesive")
		(11 "B.Adhes" user "B.Adhesive")
		(13 "F.Paste" user "Package Geometry/Pastemask Top")
		(15 "B.Paste" user "Package Geometry/Pastemask Bottom")
		(5 "F.SilkS" user "Ref Des/Silkscreen Top")
		(7 "B.SilkS" user "Ref Des/Silkscreen Bottom")
		(1 "F.Mask" user "Board Geometry/Soldermask Top")
		(3 "B.Mask" user "Board Geometry/Soldermask Bottom")
		(17 "Dwgs.User" user "User.Drawings")
		(19 "Cmts.User" user "User.Comments")
		(21 "Eco1.User" user "User.Eco1")
		(23 "Eco2.User" user "User.Eco2")
		(25 "Edge.Cuts" user "Board Geometry/Outline")
		(27 "Margin" user)
		(31 "F.CrtYd" user "Package Geometry/Place Bound Top")
		(29 "B.CrtYd" user "Package Geometry/Place Bound Bottom")
		(35 "F.Fab" user "Ref Des/Assembly Top")
		(33 "B.Fab" user "Ref Des/Assembly Bottom")
	)
	(footprint ""
		(layer "F.Cu")
		(at 78.267814 -51.019456)
		(property "Reference" "PC386"
			(at 0 0 0)
			(layer "F.SilkS")
			(hide yes)
			(effects
				(font
					(size 1.27 1.27)
				)
			)
		)
		(property "Value" ""
			(at 0 0 0)
			(layer "F.Fab")
			(effects
				(font
					(size 1.27 1.27)
				)
			)
		)
		(duplicate_pad_numbers_are_jumpers no)
		(fp_line
			(start -0.7874 -0.4064)
			(end 0.7874 -0.4064)
			(stroke
				(width 0.1524)
				(type default)
			)
			(layer "F.SilkS")
		)
		(fp_line
			(start -0.7874 0.4064)
			(end -0.7874 -0.4064)
			(stroke
				(width 0.1524)
				(type default)
			)
			(layer "F.SilkS")
		)
		(fp_line
			(start 0.7874 -0.4064)
			(end 0.7874 0.4064)
			(stroke
				(width 0.1524)
				(type default)
			)
			(layer "F.SilkS")
		)
		(fp_line
			(start 0.7874 0.4064)
			(end -0.7874 0.4064)
			(stroke
				(width 0.1524)
				(type default)
			)
			(layer "F.SilkS")
		)
		(fp_line
			(start -0.6858 -0.3048)
			(end -0.1016 -0.3048)
			(stroke
				(width 0.1)
				(type default)
			)
			(layer "F.Fab")
		)
		(fp_line
			(start -0.6858 0.3048)
			(end -0.6858 -0.3048)
			(stroke
				(width 0.1)
				(type default)
			)
			(layer "F.Fab")
		)
		(fp_line
			(start -0.1016 -0.3048)
			(end -0.1016 -0.2794)
			(stroke
				(width 0.1)
				(type default)
			)
			(layer "F.Fab")
		)
		(fp_line
			(start -0.1016 -0.2794)
			(end 0.1016 -0.2794)
			(stroke
				(width 0.1)
				(type default)
			)
			(layer "F.Fab")
		)
		(fp_line
			(start -0.1016 0.2794)
			(end -0.1016 0.3048)
			(stroke
				(width 0.1)
				(type default)
			)
			(layer "F.Fab")
		)
		(fp_line
			(start -0.1016 0.3048)
			(end -0.6858 0.3048)
			(stroke
				(width 0.1)
				(type default)
			)
			(layer "F.Fab")
		)
		(fp_line
			(start 0.1016 -0.3048)
			(end 0.6858 -0.3048)
			(stroke
				(width 0.1)
				(type default)
			)
			(layer "F.Fab")
		)
		(fp_line
			(start 0.1016 -0.2794)
			(end 0.1016 -0.3048)
			(stroke
				(width 0.1)
				(type default)
			)
			(layer "F.Fab")
		)
		(fp_line
			(start 0.1016 0.2794)
			(end -0.1016 0.2794)
			(stroke
				(width 0.1)
				(type default)
			)
			(layer "F.Fab")
		)
		(fp_line
			(start 0.1016 0.3048)
			(end 0.1016 0.2794)
			(stroke
				(width 0.1)
				(type default)
			)
			(layer "F.Fab")
		)
		(fp_line
			(start 0.6858 -0.3048)
			(end 0.6858 0.3048)
			(stroke
				(width 0.1)
				(type default)
			)
			(layer "F.Fab")
		)
		(fp_line
			(start 0.6858 0.3048)
			(end 0.1016 0.3048)
			(stroke
				(width 0.1)
				(type default)
			)
			(layer "F.Fab")
		)
		(pad "1" smd rect
			(at -0.40005 0 180)
			(size 0.4572 0.508)
			(layers "F.Cu" "F.Mask" "F.Paste")
			(net "P12V_SSD2_SS")
		)
		(pad "2" smd rect
			(at 0.40005 0 180)
			(size 0.4572 0.508)
			(layers "F.Cu" "F.Mask" "F.Paste")
			(net "GND")
		)
	)
	(footprint ""
		(layer "F.Cu")
		(at 353.196398 -205.150466 -90)
		(property "Reference" "R5779"
			(at 0 0 270)
			(layer "F.SilkS")
			(hide yes)
			(effects
				(font
					(size 1.27 1.27)
				)
			)
		)
		(property "Value" ""
			(at 0 0 270)
			(layer "F.Fab")
			(effects
				(font
					(size 1.27 1.27)
				)
			)
		)
		(duplicate_pad_numbers_are_jumpers no)
		(fp_line
			(start -0.7874 0.4064)
			(end -0.7874 -0.4064)
			(stroke
				(width 0.1524)
				(type default)
			)
			(layer "F.SilkS")
		)
		(fp_line
			(start 0.7874 0.4064)
			(end -0.7874 0.4064)
			(stroke
				(width 0.1524)
				(type default)
			)
			(layer "F.SilkS")
		)
		(fp_line
			(start -0.7874 -0.4064)
			(end 0.7874 -0.4064)
			(stroke
				(width 0.1524)
				(type default)
			)
			(layer "F.SilkS")
		)
		(fp_line
			(start 0.7874 -0.4064)
			(end 0.7874 0.4064)
			(stroke
				(width 0.1524)
				(type default)
			)
			(layer "F.SilkS")
		)
		(fp_line
			(start -0.67945 0.3048)
			(end -0.67945 -0.305054)
			(stroke
				(width 0.1)
				(type default)
			)
			(layer "F.Fab")
		)
		(fp_line
			(start -0.12065 0.3048)
			(end -0.67945 0.3048)
			(stroke
				(width 0.1)
				(type default)
			)
			(layer "F.Fab")
		)
		(fp_line
			(start 0.120396 0.3048)
			(end 0.120396 0.2794)
			(stroke
				(width 0.1)
				(type default)
			)
			(layer "F.Fab")
		)
		(fp_line
			(start 0.67945 0.3048)
			(end 0.120396 0.3048)
			(stroke
				(width 0.1)
				(type default)
			)
			(layer "F.Fab")
		)
		(fp_line
			(start -0.12065 0.2794)
			(end -0.12065 0.3048)
			(stroke
				(width 0.1)
				(type default)
			)
			(layer "F.Fab")
		)
		(fp_line
			(start 0.120396 0.2794)
			(end -0.12065 0.2794)
			(stroke
				(width 0.1)
				(type default)
			)
			(layer "F.Fab")
		)
		(fp_line
			(start -0.12065 -0.2794)
			(end 0.12065 -0.2794)
			(stroke
				(width 0.1)
				(type default)
			)
			(layer "F.Fab")
		)
		(fp_line
			(start 0.12065 -0.2794)
			(end 0.12065 -0.3048)
			(stroke
				(width 0.1)
				(type default)
			)
			(layer "F.Fab")
		)
		(fp_line
			(start 0.12065 -0.3048)
			(end 0.67945 -0.3048)
			(stroke
				(width 0.1)
				(type default)
			)
			(layer "F.Fab")
		)
		(fp_line
			(start 0.67945 -0.3048)
			(end 0.67945 0.3048)
			(stroke
				(width 0.1)
				(type default)
			)
			(layer "F.Fab")
		)
		(fp_line
			(start -0.67945 -0.305054)
			(end -0.12065 -0.305054)
			(stroke
				(width 0.1)
				(type default)
			)
			(layer "F.Fab")
		)
		(fp_line
			(start -0.12065 -0.305054)
			(end -0.12065 -0.2794)
			(stroke
				(width 0.1)
				(type default)
			)
			(layer "F.Fab")
		)
		(pad "1" smd circle
			(at -0.40005 0 270)
			(size 0 0)
			(layers "F.Cu" "F.Mask" "F.Paste")
			(net "FM_PFR_LED_BLUE")
		)
		(pad "2" smd circle
			(at 0.40005 0 270)
			(size 0 0)
			(layers "F.Cu" "F.Mask" "F.Paste")
			(net "FM_PFR_LED_BLUE_R")
		)
	)
	(footprint ""
		(layer "F.Cu")
		(at 149.211538 -261.434834)
		(property "Reference" "L107"
			(at 0 0 0)
			(layer "F.SilkS")
			(hide yes)
			(effects
				(font
					(size 1.27 1.27)
				)
			)
		)
		(property "Value" ""
			(at 0 0 0)
			(layer "F.Fab")
			(effects
				(font
					(size 1.27 1.27)
				)
			)
		)
		(duplicate_pad_numbers_are_jumpers no)
		(fp_line
			(start -1.63576 -0.8128)
			(end -1.63576 0.8128)
			(stroke
				(width 0.1524)
				(type default)
			)
			(layer "F.SilkS")
		)
		(fp_line
			(start -1.63576 -0.8128)
			(end 1.63576 -0.8128)
			(stroke
				(width 0.1524)
				(type default)
			)
			(layer "F.SilkS")
		)
		(fp_line
			(start 1.63576 -0.8128)
			(end 1.63576 0.8128)
			(stroke
				(width 0.1524)
				(type default)
			)
			(layer "F.SilkS")
		)
		(fp_line
			(start 1.63576 0.8128)
			(end -1.63576 0.8128)
			(stroke
				(width 0.1524)
				(type default)
			)
			(layer "F.SilkS")
		)
		(fp_line
			(start -1.56083 -0.738632)
			(end -1.56083 0.7366)
			(stroke
				(width 0.1)
				(type default)
			)
			(layer "F.Fab")
		)
		(fp_line
			(start -1.56083 0.7366)
			(end -1.524 0.7366)
			(stroke
				(width 0.1)
				(type default)
			)
			(layer "F.Fab")
		)
		(fp_line
			(start -1.524 0.7366)
			(end 1.524 0.7366)
			(stroke
				(width 0.1)
				(type default)
			)
			(layer "F.Fab")
		)
		(fp_line
			(start 1.524 0.7366)
			(end 1.560576 0.7366)
			(stroke
				(width 0.1)
				(type default)
			)
			(layer "F.Fab")
		)
		(fp_line
			(start 1.560576 -0.738632)
			(end -1.56083 -0.738632)
			(stroke
				(width 0.1)
				(type default)
			)
			(layer "F.Fab")
		)
		(fp_line
			(start 1.560576 0.7366)
			(end 1.560576 -0.738632)
			(stroke
				(width 0.1)
				(type default)
			)
			(layer "F.Fab")
		)
		(pad "1" smd rect
			(at -0.94996 0 180)
			(size 1.1176 1.3716)
			(layers "F.Cu" "F.Mask" "F.Paste")
			(net "P1V8_PLL0_PEX1")
		)
		(pad "2" smd rect
			(at 0.94996 0 180)
			(size 1.1176 1.3716)
			(layers "F.Cu" "F.Mask" "F.Paste")
			(net "PCEPLL3_VDDA18_PEX1")
		)
	)
	(footprint ""
		(layer "F.Cu")
		(at 132.531612 -162.003994 -90)
		(property "Reference" "R946"
			(at 0 0 270)
			(layer "F.SilkS")
			(hide yes)
			(effects
				(font
					(size 1.27 1.27)
				)
			)
		)
		(property "Value" ""
			(at 0 0 270)
			(layer "F.Fab")
			(effects
				(font
					(size 1.27 1.27)
				)
			)
		)
		(duplicate_pad_numbers_are_jumpers no)
		(fp_line
			(start -0.7874 0.4064)
			(end -0.7874 -0.4064)
			(stroke
				(width 0.1524)
				(type default)
			)
			(layer "F.SilkS")
		)
		(fp_line
			(start 0.7874 0.4064)
			(end -0.7874 0.4064)
			(stroke
				(width 0.1524)
				(type default)
			)
			(layer "F.SilkS")
		)
		(fp_line
			(start -0.7874 -0.4064)
			(end 0.7874 -0.4064)
			(stroke
				(width 0.1524)
				(type default)
			)
			(layer "F.SilkS")
		)
		(fp_line
			(start 0.7874 -0.4064)
			(end 0.7874 0.4064)
			(stroke
				(width 0.1524)
				(type default)
			)
			(layer "F.SilkS")
		)
		(fp_line
			(start -0.67945 0.3048)
			(end -0.67945 -0.305054)
			(stroke
				(width 0.1)
				(type default)
			)
			(layer "F.Fab")
		)
		(fp_line
			(start -0.12065 0.3048)
			(end -0.67945 0.3048)
			(stroke
				(width 0.1)
				(type default)
			)
			(layer "F.Fab")
		)
		(fp_line
			(start 0.120396 0.3048)
			(end 0.120396 0.2794)
			(stroke
				(width 0.1)
				(type default)
			)
			(layer "F.Fab")
		)
		(fp_line
			(start 0.67945 0.3048)
			(end 0.120396 0.3048)
			(stroke
				(width 0.1)
				(type default)
			)
			(layer "F.Fab")
		)
		(fp_line
			(start -0.12065 0.2794)
			(end -0.12065 0.3048)
			(stroke
				(width 0.1)
				(type default)
			)
			(layer "F.Fab")
		)
		(fp_line
			(start 0.120396 0.2794)
			(end -0.12065 0.2794)
			(stroke
				(width 0.1)
				(type default)
			)
			(layer "F.Fab")
		)
		(fp_line
			(start -0.12065 -0.2794)
			(end 0.12065 -0.2794)
			(stroke
				(width 0.1)
				(type default)
			)
			(layer "F.Fab")
		)
		(fp_line
			(start 0.12065 -0.2794)
			(end 0.12065 -0.3048)
			(stroke
				(width 0.1)
				(type default)
			)
			(layer "F.Fab")
		)
		(fp_line
			(start 0.12065 -0.3048)
			(end 0.67945 -0.3048)
			(stroke
				(width 0.1)
				(type default)
			)
			(layer "F.Fab")
		)
		(fp_line
			(start 0.67945 -0.3048)
			(end 0.67945 0.3048)
			(stroke
				(width 0.1)
				(type default)
			)
			(layer "F.Fab")
		)
		(fp_line
			(start -0.67945 -0.305054)
			(end -0.12065 -0.305054)
			(stroke
				(width 0.1)
				(type default)
			)
			(layer "F.Fab")
		)
		(fp_line
			(start -0.12065 -0.305054)
			(end -0.12065 -0.2794)
			(stroke
				(width 0.1)
				(type default)
			)
			(layer "F.Fab")
		)
		(pad "1" smd circle
			(at -0.40005 0 270)
			(size 0 0)
			(layers "F.Cu" "F.Mask" "F.Paste")
			(net "HP_NIC2_EN")
		)
		(pad "2" smd circle
			(at 0.40005 0 270)
			(size 0 0)
			(layers "F.Cu" "F.Mask" "F.Paste")
			(net "P12V_NIC2_CO_EN")
		)
	)
	(footprint ""
		(layer "F.Cu")
		(at 250.631198 -123.903994 -90)
		(property "Reference" "PC455"
			(at 0 0 270)
			(layer "F.SilkS")
			(hide yes)
			(effects
				(font
					(size 1.27 1.27)
				)
			)
		)
		(property "Value" ""
			(at 0 0 270)
			(layer "F.Fab")
			(effects
				(font
					(size 1.27 1.27)
				)
			)
		)
		(duplicate_pad_numbers_are_jumpers no)
		(fp_line
			(start -1.524 0.762)
			(end -1.524 -0.762)
			(stroke
				(width 0.1524)
				(type default)
			)
			(layer "F.SilkS")
		)
		(fp_line
			(start 1.524 0.762)
			(end -1.524 0.762)
			(stroke
				(width 0.1524)
				(type default)
			)
			(layer "F.SilkS")
		)
		(fp_line
			(start -1.524 -0.762)
			(end 1.524 -0.762)
			(stroke
				(width 0.1524)
				(type default)
			)
			(layer "F.SilkS")
		)
		(fp_line
			(start 1.524 -0.762)
			(end 1.524 0.762)
			(stroke
				(width 0.1524)
				(type default)
			)
			(layer "F.SilkS")
		)
		(fp_line
			(start -1.1049 0.724916)
			(end 1.1049 0.724916)
			(stroke
				(width 0.1)
				(type default)
			)
			(layer "F.Fab")
		)
		(fp_line
			(start 1.1049 0.724916)
			(end 1.1049 -0.724916)
			(stroke
				(width 0.1)
				(type default)
			)
			(layer "F.Fab")
		)
		(fp_line
			(start -1.1049 -0.724916)
			(end -1.1049 0.724916)
			(stroke
				(width 0.1)
				(type default)
			)
			(layer "F.Fab")
		)
		(fp_line
			(start 1.1049 -0.724916)
			(end -1.1049 -0.724916)
			(stroke
				(width 0.1)
				(type default)
			)
			(layer "F.Fab")
		)
		(pad "1" smd rect
			(at -0.889 0 90)
			(size 1.016 1.27)
			(layers "F.Cu" "F.Mask" "F.Paste")
			(net "P3V3_NIC4")
		)
		(pad "2" smd rect
			(at 0.889 0 90)
			(size 1.016 1.27)
			(layers "F.Cu" "F.Mask" "F.Paste")
			(net "GND")
		)
	)
	(footprint ""
		(layer "F.Cu")
		(at 212.574886 -231.150922 90)
		(property "Reference" "R1542"
			(at 0 0 90)
			(layer "F.SilkS")
			(hide yes)
			(effects
				(font
					(size 1.27 1.27)
				)
			)
		)
		(property "Value" ""
			(at 0 0 90)
			(layer "F.Fab")
			(effects
				(font
					(size 1.27 1.27)
				)
			)
		)
		(duplicate_pad_numbers_are_jumpers no)
		(fp_line
			(start 0.7874 -0.4064)
			(end 0.7874 0.4064)
			(stroke
				(width 0.1524)
				(type default)
			)
			(layer "F.SilkS")
		)
		(fp_line
			(start -0.7874 -0.4064)
			(end 0.7874 -0.4064)
			(stroke
				(width 0.1524)
				(type default)
			)
			(layer "F.SilkS")
		)
		(fp_line
			(start 0.7874 0.4064)
			(end -0.7874 0.4064)
			(stroke
				(width 0.1524)
				(type default)
			)
			(layer "F.SilkS")
		)
		(fp_line
			(start -0.7874 0.4064)
			(end -0.7874 -0.4064)
			(stroke
				(width 0.1524)
				(type default)
			)
			(layer "F.SilkS")
		)
		(fp_line
			(start -0.12065 -0.305054)
			(end -0.12065 -0.2794)
			(stroke
				(width 0.1)
				(type default)
			)
			(layer "F.Fab")
		)
		(fp_line
			(start -0.67945 -0.305054)
			(end -0.12065 -0.305054)
			(stroke
				(width 0.1)
				(type default)
			)
			(layer "F.Fab")
		)
		(fp_line
			(start 0.67945 -0.3048)
			(end 0.67945 0.3048)
			(stroke
				(width 0.1)
				(type default)
			)
			(layer "F.Fab")
		)
		(fp_line
			(start 0.12065 -0.3048)
			(end 0.67945 -0.3048)
			(stroke
				(width 0.1)
				(type default)
			)
			(layer "F.Fab")
		)
		(fp_line
			(start 0.12065 -0.2794)
			(end 0.12065 -0.3048)
			(stroke
				(width 0.1)
				(type default)
			)
			(layer "F.Fab")
		)
		(fp_line
			(start -0.12065 -0.2794)
			(end 0.12065 -0.2794)
			(stroke
				(width 0.1)
				(type default)
			)
			(layer "F.Fab")
		)
		(fp_line
			(start 0.120396 0.2794)
			(end -0.12065 0.2794)
			(stroke
				(width 0.1)
				(type default)
			)
			(layer "F.Fab")
		)
		(fp_line
			(start -0.12065 0.2794)
			(end -0.12065 0.3048)
			(stroke
				(width 0.1)
				(type default)
			)
			(layer "F.Fab")
		)
		(fp_line
			(start 0.67945 0.3048)
			(end 0.120396 0.3048)
			(stroke
				(width 0.1)
				(type default)
			)
			(layer "F.Fab")
		)
		(fp_line
			(start 0.120396 0.3048)
			(end 0.120396 0.2794)
			(stroke
				(width 0.1)
				(type default)
			)
			(layer "F.Fab")
		)
		(fp_line
			(start -0.12065 0.3048)
			(end -0.67945 0.3048)
			(stroke
				(width 0.1)
				(type default)
			)
			(layer "F.Fab")
		)
		(fp_line
			(start -0.67945 0.3048)
			(end -0.67945 -0.305054)
			(stroke
				(width 0.1)
				(type default)
			)
			(layer "F.Fab")
		)
		(pad "1" smd circle
			(at -0.40005 0 90)
			(size 0 0)
			(layers "F.Cu" "F.Mask" "F.Paste")
			(net "SMB_PEX_LS_R_SDA")
		)
		(pad "2" smd circle
			(at 0.40005 0 90)
			(size 0 0)
			(layers "F.Cu" "F.Mask" "F.Paste")
			(net "SMB_PEX0_SDA")
		)
	)
	(footprint ""
		(layer "F.Cu")
		(at 215.488774 -109.058202)
		(property "Reference" "R716"
			(at 0 0 0)
			(layer "F.SilkS")
			(hide yes)
			(effects
				(font
					(size 1.27 1.27)
				)
			)
		)
		(property "Value" ""
			(at 0 0 0)
			(layer "F.Fab")
			(effects
				(font
					(size 1.27 1.27)
				)
			)
		)
		(duplicate_pad_numbers_are_jumpers no)
		(fp_line
			(start -3.937508 -1.8796)
			(end -3.937508 1.8796)
			(stroke
				(width 0.1524)
				(type default)
			)
			(layer "F.SilkS")
		)
		(fp_line
			(start -3.937508 1.8796)
			(end 3.937508 1.8796)
			(stroke
				(width 0.1524)
				(type default)
			)
			(layer "F.SilkS")
		)
		(fp_line
			(start 3.937508 -1.8796)
			(end -3.937508 -1.8796)
			(stroke
				(width 0.1524)
				(type default)
			)
			(layer "F.SilkS")
		)
		(fp_line
			(start 3.937508 1.8796)
			(end 3.937508 -1.8796)
			(stroke
				(width 0.1524)
				(type default)
			)
			(layer "F.SilkS")
		)
		(fp_line
			(start -3.275076 -1.674876)
			(end -3.275076 1.674876)
			(stroke
				(width 0.1)
				(type default)
			)
			(layer "F.Fab")
		)
		(fp_line
			(start -3.275076 1.674876)
			(end 3.275076 1.674876)
			(stroke
				(width 0.1)
				(type default)
			)
			(layer "F.Fab")
		)
		(fp_line
			(start 3.275076 -1.674876)
			(end -3.275076 -1.674876)
			(stroke
				(width 0.1)
				(type default)
			)
			(layer "F.Fab")
		)
		(fp_line
			(start 3.275076 1.674876)
			(end 3.275076 -1.674876)
			(stroke
				(width 0.1)
				(type default)
			)
			(layer "F.Fab")
		)
		(pad "1" smd rect
			(at -2.350008 0)
			(size 2.921 3.5052)
			(layers "F.Cu" "F.Mask" "F.Paste")
			(net "P12V_NIC3")
		)
		(pad "2" smd rect
			(at 2.350008 0)
			(size 2.921 3.5052)
			(layers "F.Cu" "F.Mask" "F.Paste")
			(net "P12V_NIC3_R")
		)
	)
)
